# BASEBOARD_FAB2 (Tioga Pass) — schematic netlist excerpt (pin names and nets, part order shuffled) for the footprints in the layout excerpt that follows; sources: Cadence DE-HDL packaged netlist, KiCad conversion of Wiwynn_Tioga_Pass_MB.brd

C4B15  CAP  0.1UF 25V 10% X7R  pkg 0603LF  page 234 : A = VR_PVPP_KLM_PHASE ; B = VR_PVPP_KLM_BOOT_R

Q9A1  NPN_DUAL  MBT3904 EMPTY  pkg SSOPLF  page 111
  E(0)  = XDP_CPU_GTL_TCK_R2
  B(0)  = XDP_CPU_TCK_BUF
  C(0)  = P3V3
  E(0)  = XDP_CPU_TCK0
  B(0)  = XDP_CPU_TCK_BUF
  C(0)  = XDP_CPU_TCK_BUF

R9B8  RES  1.00K 1% CHIP  pkg 0402  page 167 : A = PD_TMP421_1_A0 ; B = GND

(kicad_pcb
	(version 20260206)
	(generator "pcbnew")
	(generator_version "10.0")
	(general
		(thickness 1.6)
		(legacy_teardrops no)
	)
	(paper "A4")
	(title_block
		(title "Wiwynn_Tioga_Pass_MB.brd")
		(comment 1 "Tioga Pass / footprints 1022-1024 of 4770")
	)
	(layers
		(0 "F.Cu" signal "TOP")
		(4 "In1.Cu" signal "L2GND")
		(6 "In2.Cu" signal "L3")
		(8 "In3.Cu" signal "L4GND")
		(10 "In4.Cu" signal "L5")
		(12 "In5.Cu" signal "L6GND")
		(14 "In6.Cu" signal "L7VCC")
		(16 "In7.Cu" signal "L8VCC")
		(18 "In8.Cu" signal "L9GND")
		(20 "In9.Cu" signal "L10")
		(22 "In10.Cu" signal "L11GND")
		(24 "In11.Cu" signal "L12")
		(26 "In12.Cu" signal "L13GND")
		(2 "B.Cu" signal "BOTTOM")
		(9 "F.Adhes" user "F.Adhesive")
		(11 "B.Adhes" user "B.Adhesive")
		(13 "F.Paste" user "Package Geometry/Pastemask Top")
		(15 "B.Paste" user "Package Geometry/Pastemask Bottom")
		(5 "F.SilkS" user "Ref Des/Silkscreen Top")
		(7 "B.SilkS" user "Ref Des/Silkscreen Bottom")
		(1 "F.Mask" user "Board Geometry/Soldermask Top")
		(3 "B.Mask" user "Board Geometry/Soldermask Bottom")
		(17 "Dwgs.User" user "User.Drawings")
		(19 "Cmts.User" user "User.Comments")
		(21 "Eco1.User" user "User.Eco1")
		(23 "Eco2.User" user "User.Eco2")
		(25 "Edge.Cuts" user "Board Geometry/Outline")
		(27 "Margin" user)
		(31 "F.CrtYd" user "Package Geometry/Place Bound Top")
		(29 "B.CrtYd" user "Package Geometry/Place Bound Bottom")
		(35 "F.Fab" user "Ref Des/Assembly Top")
		(33 "B.Fab" user "Ref Des/Assembly Bottom")
	)
	(footprint ""
		(layer "F.Cu")
		(at 489.19892 -120.75922 90)
		(property "Reference" "R9B8"
			(at 0 0 90)
			(layer "F.SilkS")
			(hide yes)
			(effects
				(font
					(size 1.27 1.27)
				)
			)
		)
		(property "Value" ""
			(at 0 0 90)
			(layer "F.Fab")
			(effects
				(font
					(size 1.27 1.27)
				)
			)
		)
		(duplicate_pad_numbers_are_jumpers no)
		(fp_rect
			(start -0.2794 -0.1016)
			(end 0.2794 0.9906)
			(stroke
				(width 0)
				(type default)
			)
			(fill no)
			(layer "F.CrtYd")
		)
		(fp_line
			(start 0.2794 -0.1016)
			(end -0.2794 -0.1016)
			(stroke
				(width 0.1)
				(type default)
			)
			(layer "F.Fab")
		)
		(fp_line
			(start -0.2794 -0.1016)
			(end -0.2794 0.9906)
			(stroke
				(width 0.1)
				(type default)
			)
			(layer "F.Fab")
		)
		(fp_line
			(start 0.2794 0.9906)
			(end 0.2794 -0.1016)
			(stroke
				(width 0.1)
				(type default)
			)
			(layer "F.Fab")
		)
		(fp_line
			(start -0.2794 0.9906)
			(end 0.2794 0.9906)
			(stroke
				(width 0.1)
				(type default)
			)
			(layer "F.Fab")
		)
		(pad "1" smd rect
			(at 0 0 90)
			(size 0.508 0.508)
			(layers "F.Cu" "F.Mask" "F.Paste")
			(net "PD_TMP421_1_A0")
		)
		(pad "2" smd rect
			(at 0 0.889 90)
			(size 0.508 0.508)
			(layers "F.Cu" "F.Mask" "F.Paste")
			(net "GND")
		)
		(zone
			(layer "F.Cu")
			(hatch none 0.5)
			(connect_pads
				(clearance 0)
			)
			(min_thickness 0.25)
			(keepout
				(tracks allowed)
				(vias not_allowed)
				(pads allowed)
				(copperpour not_allowed)
				(footprints allowed)
			)
			(placement
				(enabled no)
				(sheetname "")
			)
			(fill
				(thermal_gap 0.5)
				(thermal_bridge_width 0.5)
				(island_removal_mode 0)
			)
			(polygon
				(pts
					(xy 489.45292 -120.50522) (xy 489.83392 -120.50522) (xy 489.83392 -121.01322) (xy 489.45292 -121.01322)
				)
			)
		)
		(zone
			(layer "F.Cu")
			(hatch none 0.5)
			(connect_pads
				(clearance 0)
			)
			(min_thickness 0.25)
			(keepout
				(tracks not_allowed)
				(vias allowed)
				(pads allowed)
				(copperpour not_allowed)
				(footprints allowed)
			)
			(placement
				(enabled no)
				(sheetname "")
			)
			(fill
				(thermal_gap 0.5)
				(thermal_bridge_width 0.5)
				(island_removal_mode 0)
			)
			(polygon
				(pts
					(xy 489.45292 -120.50522) (xy 489.83392 -120.50522) (xy 489.83392 -121.01322) (xy 489.45292 -121.01322)
				)
			)
		)
	)
	(footprint ""
		(layer "F.Cu")
		(at 169.51833 -133.705092 90)
		(property "Reference" "C4B15"
			(at 0 0 90)
			(layer "F.SilkS")
			(hide yes)
			(effects
				(font
					(size 1.27 1.27)
				)
			)
		)
		(property "Value" ""
			(at 0 0 90)
			(layer "F.Fab")
			(effects
				(font
					(size 1.27 1.27)
				)
			)
		)
		(duplicate_pad_numbers_are_jumpers no)
		(fp_poly
			(pts
				(xy -0.4953 -0.2032) (xy 0.4953 -0.2032) (xy 0.4953 1.6002) (xy -0.4953 1.6002)
			)
			(stroke
				(width 0)
				(type default)
			)
			(fill no)
			(layer "F.CrtYd")
		)
		(fp_line
			(start 0.4953 -0.2032)
			(end 0.4953 1.6002)
			(stroke
				(width 0.1)
				(type default)
			)
			(layer "F.Fab")
		)
		(fp_line
			(start -0.4953 -0.2032)
			(end 0.4953 -0.2032)
			(stroke
				(width 0.1)
				(type default)
			)
			(layer "F.Fab")
		)
		(fp_line
			(start 0.4953 1.6002)
			(end -0.4953 1.6002)
			(stroke
				(width 0.1)
				(type default)
			)
			(layer "F.Fab")
		)
		(fp_line
			(start -0.4953 1.6002)
			(end -0.4953 -0.2032)
			(stroke
				(width 0.1)
				(type default)
			)
			(layer "F.Fab")
		)
		(pad "1" smd rect
			(at 0 0 90)
			(size 0.762 0.889)
			(layers "F.Cu" "F.Mask" "F.Paste")
			(net "VR_PVPP_KLM_PHASE")
		)
		(pad "2" smd rect
			(at 0 1.397 90)
			(size 0.762 0.889)
			(layers "F.Cu" "F.Mask" "F.Paste")
			(net "VR_PVPP_KLM_BOOT_R")
		)
		(zone
			(layer "F.Cu")
			(hatch none 0.5)
			(connect_pads
				(clearance 0)
			)
			(min_thickness 0.25)
			(keepout
				(tracks not_allowed)
				(vias allowed)
				(pads allowed)
				(copperpour not_allowed)
				(footprints allowed)
			)
			(placement
				(enabled no)
				(sheetname "")
			)
			(fill
				(thermal_gap 0.5)
				(thermal_bridge_width 0.5)
				(island_removal_mode 0)
			)
			(polygon
				(pts
					(xy 169.96283 -133.324092) (xy 169.96283 -134.086092) (xy 170.47083 -134.086092) (xy 170.47083 -133.324092)
				)
			)
		)
	)
	(footprint ""
		(layer "F.Cu")
		(at 454.279 -157.607)
		(property "Reference" "Q9A1"
			(at 2.28854 2.19075 180)
			(unlocked yes)
			(layer "F.SilkS")
			(effects
				(font
					(size 0.7874 0.5842)
					(thickness 0.1524)
				)
				(justify left)
			)
		)
		(property "Value" ""
			(at 0 0 0)
			(layer "F.Fab")
			(effects
				(font
					(size 1.27 1.27)
				)
			)
		)
		(duplicate_pad_numbers_are_jumpers no)
		(fp_circle
			(center -0.848614 -0.6477)
			(end -0.721614 -0.6477)
			(stroke
				(width 0.254)
				(type default)
			)
			(fill no)
			(layer "F.SilkS")
		)
		(fp_poly
			(pts
				(xy 0.21463 -0.450088) (xy 1.56337 -0.450088) (xy 1.56337 1.75006) (xy 0.21463 1.75006)
			)
			(stroke
				(width 0)
				(type default)
			)
			(fill no)
			(layer "F.CrtYd")
		)
		(fp_line
			(start 0.21463 -0.450088)
			(end 1.56337 -0.450088)
			(stroke
				(width 0.1)
				(type default)
			)
			(layer "F.Fab")
		)
		(fp_line
			(start 0.21463 1.75006)
			(end 0.21463 -0.450088)
			(stroke
				(width 0.1)
				(type default)
			)
			(layer "F.Fab")
		)
		(fp_line
			(start 1.56337 -0.450088)
			(end 1.56337 1.75006)
			(stroke
				(width 0.1)
				(type default)
			)
			(layer "F.Fab")
		)
		(fp_line
			(start 1.56337 1.75006)
			(end 0.21463 1.75006)
			(stroke
				(width 0.1)
				(type default)
			)
			(layer "F.Fab")
		)
		(fp_circle
			(center -0.848614 -0.6477)
			(end -0.721614 -0.6477)
			(stroke
				(width 0.254)
				(type default)
			)
			(fill no)
			(layer "F.Fab")
		)
		(pad "1" smd rect
			(at 0 0)
			(size 1.016 0.381)
			(layers "F.Cu" "F.Mask" "F.Paste")
			(net "XDP_CPU_GTL_TCK_R2")
		)
		(pad "2" smd rect
			(at 0 0.649986)
			(size 1.016 0.381)
			(layers "F.Cu" "F.Mask" "F.Paste")
			(net "XDP_CPU_TCK_BUF")
		)
		(pad "3" smd rect
			(at 0 1.299972)
			(size 1.016 0.381)
			(layers "F.Cu" "F.Mask" "F.Paste")
			(net "P3V3")
		)
		(pad "4" smd rect
			(at 1.778 1.299972)
			(size 1.016 0.381)
			(layers "F.Cu" "F.Mask" "F.Paste")
			(net "XDP_CPU_TCK0")
		)
		(pad "5" smd rect
			(at 1.778 0.649986)
			(size 1.016 0.381)
			(layers "F.Cu" "F.Mask" "F.Paste")
			(net "XDP_CPU_TCK_BUF")
		)
		(pad "6" smd rect
			(at 1.778 0)
			(size 1.016 0.381)
			(layers "F.Cu" "F.Mask" "F.Paste")
			(net "XDP_CPU_TCK_BUF")
		)
	)
)
